(kicad_pcb
	(version 20241229)
	(generator "pcbnew")
	(generator_version "9.0")
	(general
		(thickness 1.599998)
		(legacy_teardrops no)
	)
	(paper "A4")
	(title_block
		(date "2023-02-12")
		(rev "1.1.5")
		(comment 9 "footprints 297-302 of 473")
	)
	(layers
		(0 "F.Cu" signal)
		(4 "In1.Cu" power "In1.GND")
		(6 "In2.Cu" signal)
		(8 "In3.Cu" power "In3.GND")
		(10 "In4.Cu" power "In4.VCC")
		(12 "In5.Cu" signal)
		(14 "In6.Cu" power "In6.VCC")
		(2 "B.Cu" signal)
		(9 "F.Adhes" user "F.Adhesive")
		(11 "B.Adhes" user "B.Adhesive")
		(13 "F.Paste" user)
		(15 "B.Paste" user)
		(5 "F.SilkS" user "F.Silkscreen")
		(7 "B.SilkS" user "B.Silkscreen")
		(1 "F.Mask" user)
		(3 "B.Mask" user)
		(17 "Dwgs.User" user "User.Drawings")
		(19 "Cmts.User" user "User.Comments")
		(21 "Eco1.User" user "User.Eco1")
		(23 "Eco2.User" user "User.Eco2")
		(25 "Edge.Cuts" user)
		(27 "Margin" user)
		(31 "F.CrtYd" user "F.Courtyard")
		(29 "B.CrtYd" user "B.Courtyard")
		(35 "F.Fab" user)
		(33 "B.Fab" user)
	)
	(footprint "antmicro-footprints:R_0402_1005Metric"
		(layer "F.Cu")
		(at 117.697806 89.074 180)
		(descr "Resistor SMD 0402")
		(tags "resistor SMD 0402")
		(property "Reference" "R131"
			(at 0.897806 3.574 180)
			(layer "F.SilkS")
			(effects
				(font
					(size 0.7 0.7)
					(thickness 0.15)
				)
				(justify left bottom)
			)
		)
		(property "Value" "R_0R_0402"
			(at 0 1.4 180)
			(layer "F.Fab")
			(effects
				(font
					(size 0.7 0.7)
					(thickness 0.15)
				)
				(justify left bottom)
			)
		)
		(property "Description" "0R resistor in 0402 package with unspecified tolerance"
			(at 0 0 180)
			(layer "F.Fab")
			(hide yes)
			(effects
				(font
					(size 1.27 1.27)
					(thickness 0.15)
				)
			)
		)
		(property "Author" "Antmicro"
			(at 235.395612 178.148 0)
			(layer "F.Fab")
			(hide yes)
			(effects
				(font
					(size 1 1)
					(thickness 0.15)
				)
			)
		)
		(property "Current" "1A"
			(at 235.395612 178.148 0)
			(layer "F.Fab")
			(hide yes)
			(effects
				(font
					(size 1 1)
					(thickness 0.15)
				)
			)
		)
		(property "License" "Apache-2.0"
			(at 235.395612 178.148 0)
			(layer "F.Fab")
			(hide yes)
			(effects
				(font
					(size 1 1)
					(thickness 0.15)
				)
			)
		)
		(property "MPN" "ERJ2GE0R00X"
			(at 235.395612 178.148 0)
			(layer "F.Fab")
			(hide yes)
			(effects
				(font
					(size 1 1)
					(thickness 0.15)
				)
			)
		)
		(property "Manufacturer" "Panasonic"
			(at 235.395612 178.148 0)
			(layer "F.Fab")
			(hide yes)
			(effects
				(font
					(size 1 1)
					(thickness 0.15)
				)
			)
		)
		(property "Tolerance" ""
			(at 235.395612 178.148 0)
			(layer "F.Fab")
			(hide yes)
			(effects
				(font
					(size 1 1)
					(thickness 0.15)
				)
			)
		)
		(property "Val" "0R"
			(at 235.395612 178.148 0)
			(layer "F.Fab")
			(hide yes)
			(effects
				(font
					(size 1 1)
					(thickness 0.15)
				)
			)
		)
		(sheetname "Supply")
		(sheetfile "supply.kicad_sch")
		(attr smd)
		(fp_rect
			(start -0.93 -0.47)
			(end 0.93 0.47)
			(stroke
				(width 0.05)
				(type solid)
			)
			(fill no)
			(layer "F.CrtYd")
		)
		(fp_rect
			(start -0.5 -0.25)
			(end 0.5 0.25)
			(stroke
				(width 0.15)
				(type solid)
			)
			(fill no)
			(layer "F.Fab")
		)
		(pad "1" smd roundrect
			(at -0.485 0 180)
			(size 0.59 0.64)
			(layers "F.Cu" "F.Mask" "F.Paste")
			(roundrect_rratio 0.25)
			(net 5 "GND")
			(pintype "passive")
		)
		(pad "2" smd roundrect
			(at 0.485 0 180)
			(size 0.59 0.64)
			(layers "F.Cu" "F.Mask" "F.Paste")
			(roundrect_rratio 0.25)
			(net 619 "/Supply/1V8_MODE")
			(pintype "passive")
		)
	)
	(footprint "antmicro-footprints:R_0402_1005Metric"
		(layer "F.Cu")
		(at 111.362806 88.974)
		(descr "Resistor SMD 0402")
		(tags "resistor SMD 0402")
		(property "Reference" "R132"
			(at -3.662806 0.326 0)
			(layer "F.SilkS")
			(effects
				(font
					(size 0.7 0.7)
					(thickness 0.15)
				)
				(justify left bottom)
			)
		)
		(property "Value" "R_0R_0402"
			(at 0 1.4 0)
			(layer "F.Fab")
			(effects
				(font
					(size 0.7 0.7)
					(thickness 0.15)
				)
				(justify left bottom)
			)
		)
		(property "Description" "0R resistor in 0402 package with unspecified tolerance"
			(at 0 0 0)
			(layer "F.Fab")
			(hide yes)
			(effects
				(font
					(size 1.27 1.27)
					(thickness 0.15)
				)
			)
		)
		(property "Author" "Antmicro"
			(at 0 0 0)
			(layer "F.Fab")
			(hide yes)
			(effects
				(font
					(size 1 1)
					(thickness 0.15)
				)
			)
		)
		(property "Current" "1A"
			(at 0 0 0)
			(layer "F.Fab")
			(hide yes)
			(effects
				(font
					(size 1 1)
					(thickness 0.15)
				)
			)
		)
		(property "License" "Apache-2.0"
			(at 0 0 0)
			(layer "F.Fab")
			(hide yes)
			(effects
				(font
					(size 1 1)
					(thickness 0.15)
				)
			)
		)
		(property "MPN" "ERJ2GE0R00X"
			(at 0 0 0)
			(layer "F.Fab")
			(hide yes)
			(effects
				(font
					(size 1 1)
					(thickness 0.15)
				)
			)
		)
		(property "Manufacturer" "Panasonic"
			(at 0 0 0)
			(layer "F.Fab")
			(hide yes)
			(effects
				(font
					(size 1 1)
					(thickness 0.15)
				)
			)
		)
		(property "Tolerance" ""
			(at 0 0 0)
			(layer "F.Fab")
			(hide yes)
			(effects
				(font
					(size 1 1)
					(thickness 0.15)
				)
			)
		)
		(property "Val" "0R"
			(at 0 0 0)
			(layer "F.Fab")
			(hide yes)
			(effects
				(font
					(size 1 1)
					(thickness 0.15)
				)
			)
		)
		(sheetname "Supply")
		(sheetfile "supply.kicad_sch")
		(attr smd)
		(fp_rect
			(start -0.93 -0.47)
			(end 0.93 0.47)
			(stroke
				(width 0.05)
				(type solid)
			)
			(fill no)
			(layer "F.CrtYd")
		)
		(fp_rect
			(start -0.5 -0.25)
			(end 0.5 0.25)
			(stroke
				(width 0.15)
				(type solid)
			)
			(fill no)
			(layer "F.Fab")
		)
		(pad "1" smd roundrect
			(at -0.485 0)
			(size 0.59 0.64)
			(layers "F.Cu" "F.Mask" "F.Paste")
			(roundrect_rratio 0.25)
			(net 5 "GND")
			(pintype "passive")
		)
		(pad "2" smd roundrect
			(at 0.485 0)
			(size 0.59 0.64)
			(layers "F.Cu" "F.Mask" "F.Paste")
			(roundrect_rratio 0.25)
			(net 620 "/Supply/1V8_SS{slash}TR")
			(pintype "passive")
		)
	)
	(footprint "antmicro-footprints:R_0402_1005Metric"
		(layer "F.Cu")
		(at 187 118.185 90)
		(descr "Resistor SMD 0402")
		(tags "resistor SMD 0402")
		(property "Reference" "R123"
			(at -3.615 0.436828 90)
			(layer "F.SilkS")
			(effects
				(font
					(size 0.7 0.7)
					(thickness 0.15)
				)
				(justify left bottom)
			)
		)
		(property "Value" "R_0R_0402"
			(at 0 1.4 90)
			(layer "F.Fab")
			(effects
				(font
					(size 0.7 0.7)
					(thickness 0.15)
				)
				(justify left bottom)
			)
		)
		(property "Description" "0R resistor in 0402 package with unspecified tolerance"
			(at 0 0 90)
			(layer "F.Fab")
			(hide yes)
			(effects
				(font
					(size 1.27 1.27)
					(thickness 0.15)
				)
			)
		)
		(property "Author" "Antmicro"
			(at 305.185 -68.815 0)
			(layer "F.Fab")
			(hide yes)
			(effects
				(font
					(size 1 1)
					(thickness 0.15)
				)
			)
		)
		(property "Current" "1A"
			(at 305.185 -68.815 0)
			(layer "F.Fab")
			(hide yes)
			(effects
				(font
					(size 1 1)
					(thickness 0.15)
				)
			)
		)
		(property "License" "Apache-2.0"
			(at 305.185 -68.815 0)
			(layer "F.Fab")
			(hide yes)
			(effects
				(font
					(size 1 1)
					(thickness 0.15)
				)
			)
		)
		(property "MPN" "ERJ2GE0R00X"
			(at 305.185 -68.815 0)
			(layer "F.Fab")
			(hide yes)
			(effects
				(font
					(size 1 1)
					(thickness 0.15)
				)
			)
		)
		(property "Manufacturer" "Panasonic"
			(at 305.185 -68.815 0)
			(layer "F.Fab")
			(hide yes)
			(effects
				(font
					(size 1 1)
					(thickness 0.15)
				)
			)
		)
		(property "Tolerance" ""
			(at 305.185 -68.815 0)
			(layer "F.Fab")
			(hide yes)
			(effects
				(font
					(size 1 1)
					(thickness 0.15)
				)
			)
		)
		(property "Val" "0R"
			(at 305.185 -68.815 0)
			(layer "F.Fab")
			(hide yes)
			(effects
				(font
					(size 1 1)
					(thickness 0.15)
				)
			)
		)
		(sheetname "Supply")
		(sheetfile "supply.kicad_sch")
		(attr smd)
		(fp_rect
			(start -0.93 -0.47)
			(end 0.93 0.47)
			(stroke
				(width 0.05)
				(type solid)
			)
			(fill no)
			(layer "F.CrtYd")
		)
		(fp_rect
			(start -0.5 -0.25)
			(end 0.5 0.25)
			(stroke
				(width 0.15)
				(type solid)
			)
			(fill no)
			(layer "F.Fab")
		)
		(pad "1" smd roundrect
			(at -0.485 0 90)
			(size 0.59 0.64)
			(layers "F.Cu" "F.Mask" "F.Paste")
			(roundrect_rratio 0.25)
			(net 597 "/Supply/1V2_VCC_INT")
			(pintype "passive")
		)
		(pad "2" smd roundrect
			(at 0.485 0 90)
			(size 0.59 0.64)
			(layers "F.Cu" "F.Mask" "F.Paste")
			(roundrect_rratio 0.25)
			(net 616 "/Supply/1V2_FSEL")
			(pintype "passive")
		)
	)
	(footprint "antmicro-footprints:R_0805_2012Metric"
		(layer "F.Cu")
		(at 192.8 111.5 90)
		(property "Reference" "R145"
			(at -1.5 1.7 90)
			(layer "F.SilkS")
			(effects
				(font
					(size 0.7 0.7)
					(thickness 0.15)
				)
				(justify left bottom)
			)
		)
		(property "Value" "R_0R_0805"
			(at 0 1.8 90)
			(layer "F.Fab")
			(effects
				(font
					(size 0.7 0.7)
					(thickness 0.15)
				)
				(justify left bottom)
			)
		)
		(property "Description" "0R resistor in 0805 package with unspecified tolerance"
			(at 0 0 90)
			(layer "F.Fab")
			(hide yes)
			(effects
				(font
					(size 1.27 1.27)
					(thickness 0.15)
				)
			)
		)
		(property "Author" "Antmicro"
			(at 304.3 -81.3 0)
			(layer "F.Fab")
			(hide yes)
			(effects
				(font
					(size 1 1)
					(thickness 0.15)
				)
			)
		)
		(property "Current" "2.5A"
			(at 304.3 -81.3 0)
			(layer "F.Fab")
			(hide yes)
			(effects
				(font
					(size 1 1)
					(thickness 0.15)
				)
			)
		)
		(property "License" "Apache-2.0"
			(at 304.3 -81.3 0)
			(layer "F.Fab")
			(hide yes)
			(effects
				(font
					(size 1 1)
					(thickness 0.15)
				)
			)
		)
		(property "MPN" "CRCW08050000Z0EA"
			(at 304.3 -81.3 0)
			(layer "F.Fab")
			(hide yes)
			(effects
				(font
					(size 1 1)
					(thickness 0.15)
				)
			)
		)
		(property "Manufacturer" "Vishay"
			(at 304.3 -81.3 0)
			(layer "F.Fab")
			(hide yes)
			(effects
				(font
					(size 1 1)
					(thickness 0.15)
				)
			)
		)
		(property "Tolerance" ""
			(at 304.3 -81.3 0)
			(layer "F.Fab")
			(hide yes)
			(effects
				(font
					(size 1 1)
					(thickness 0.15)
				)
			)
		)
		(property "Val" "0R"
			(at 304.3 -81.3 0)
			(layer "F.Fab")
			(hide yes)
			(effects
				(font
					(size 1 1)
					(thickness 0.15)
				)
			)
		)
		(sheetname "Supply")
		(sheetfile "supply.kicad_sch")
		(attr smd)
		(fp_line
			(start -0.3 -0.701)
			(end 0.298 -0.701)
			(stroke
				(width 0.15)
				(type solid)
			)
			(layer "F.SilkS")
		)
		(fp_line
			(start -0.32 0.699)
			(end 0.28 0.699)
			(stroke
				(width 0.15)
				(type solid)
			)
			(layer "F.SilkS")
		)
		(fp_rect
			(start -1.75 -0.85)
			(end 1.75 0.85)
			(stroke
				(width 0.05)
				(type solid)
			)
			(fill no)
			(layer "F.CrtYd")
		)
		(fp_line
			(start -0.951 -0.682)
			(end 0.949 -0.682)
			(stroke
				(width 0.15)
				(type solid)
			)
			(layer "F.Fab")
		)
		(fp_line
			(start 0.949 -0.677)
			(end 0.949 0.675)
			(stroke
				(width 0.15)
				(type solid)
			)
			(layer "F.Fab")
		)
		(fp_line
			(start -0.951 -0.677)
			(end -0.951 0.675)
			(stroke
				(width 0.15)
				(type solid)
			)
			(layer "F.Fab")
		)
		(fp_line
			(start -0.951 0.68)
			(end 0.949 0.68)
			(stroke
				(width 0.15)
				(type solid)
			)
			(layer "F.Fab")
		)
		(pad "1" smd roundrect
			(at -1.1 -0.001 90)
			(size 1 1.4)
			(layers "F.Cu" "F.Mask" "F.Paste")
			(roundrect_rratio 0.15)
			(net 589 "/Supply/1V2_REG")
			(pintype "passive")
		)
		(pad "2" smd roundrect
			(at 1.1 -0.001 90)
			(size 1 1.4)
			(layers "F.Cu" "F.Mask" "F.Paste")
			(roundrect_rratio 0.15)
			(net 602 "1V2_SYS")
			(pintype "passive")
		)
	)
	(footprint "antmicro-footprints:V-QFN2030-12"
		(layer "F.Cu")
		(at 126.896172 100.378992 180)
		(property "Reference" "U12"
			(at -0.903828 -2.521008 180)
			(layer "F.SilkS")
			(effects
				(font
					(size 0.7 0.7)
					(thickness 0.15)
				)
				(justify left bottom)
			)
		)
		(property "Value" "AP62600SJ-7"
			(at -4 2.2 180)
			(layer "F.Fab")
			(effects
				(font
					(size 0.7 0.7)
					(thickness 0.15)
				)
				(justify left bottom)
			)
		)
		(property "Description" "Buck Switching Regulator IC Positive Fixed 0.6V 1 Output 6A 12-VFQFN"
			(at 0 0 180)
			(layer "F.Fab")
			(hide yes)
			(effects
				(font
					(size 1.27 1.27)
					(thickness 0.15)
				)
			)
		)
		(property "Author" "Antmicro"
			(at 253.792344 200.757984 0)
			(layer "F.Fab")
			(hide yes)
			(effects
				(font
					(size 1 1)
					(thickness 0.15)
				)
			)
		)
		(property "License" "Apache-2.0"
			(at 253.792344 200.757984 0)
			(layer "F.Fab")
			(hide yes)
			(effects
				(font
					(size 1 1)
					(thickness 0.15)
				)
			)
		)
		(property "MPN" "AP62600SJ-7"
			(at 253.792344 200.757984 0)
			(layer "F.Fab")
			(hide yes)
			(effects
				(font
					(size 1 1)
					(thickness 0.15)
				)
			)
		)
		(property "Manufacturer" "Diodes Incorporated"
			(at 253.792344 200.757984 0)
			(layer "F.Fab")
			(hide yes)
			(effects
				(font
					(size 1 1)
					(thickness 0.15)
				)
			)
		)
		(sheetname "Supply")
		(sheetfile "supply.kicad_sch")
		(attr smd)
		(fp_line
			(start 1.8 1.199)
			(end 0.8 1.199)
			(stroke
				(width 0.15)
				(type solid)
			)
			(layer "F.SilkS")
		)
		(fp_line
			(start 1.8 0.998)
			(end 1.8 1.199)
			(stroke
				(width 0.15)
				(type solid)
			)
			(layer "F.SilkS")
		)
		(fp_line
			(start 1.8 -1.276)
			(end 1.8 -1.025)
			(stroke
				(width 0.15)
				(type solid)
			)
			(layer "F.SilkS")
		)
		(fp_line
			(start -0.802 1.199)
			(end -1.801 1.199)
			(stroke
				(width 0.15)
				(type solid)
			)
			(layer "F.SilkS")
		)
		(fp_line
			(start -1.801 1.199)
			(end -1.801 0.998)
			(stroke
				(width 0.15)
				(type solid)
			)
			(layer "F.SilkS")
		)
		(fp_line
			(start -1.801 -1)
			(end -1.801 -1.2)
			(stroke
				(width 0.15)
				(type solid)
			)
			(layer "F.SilkS")
		)
		(fp_line
			(start -1.801 -1.2)
			(end -0.802 -1.2)
			(stroke
				(width 0.15)
				(type solid)
			)
			(layer "F.SilkS")
		)
		(fp_circle
			(center 0.497 -1.7)
			(end 0.548 -1.7)
			(stroke
				(width 0.15)
				(type solid)
			)
			(fill yes)
			(layer "F.SilkS")
		)
		(fp_rect
			(start -2.026 -1.525)
			(end 2.023 1.524)
			(stroke
				(width 0.05)
				(type solid)
			)
			(fill no)
			(layer "F.CrtYd")
		)
		(fp_line
			(start 1.3 -1)
			(end 1.5 -0.8)
			(stroke
				(width 0.15)
				(type solid)
			)
			(layer "F.Fab")
		)
		(fp_rect
			(start -1.526 -1.025)
			(end 1.523 1.024)
			(stroke
				(width 0.15)
				(type solid)
			)
			(fill no)
			(layer "F.Fab")
		)
		(pad "1" smd rect
			(at 0.498 -0.552 90)
			(size 1.6 0.35)
			(layers "F.Cu" "F.Mask" "F.Paste")
			(net 5 "GND")
			(pinfunction "PGND")
			(pintype "passive")
		)
		(pad "2" smd rect
			(at -0.5 -0.552 90)
			(size 1.6 0.35)
			(layers "F.Cu" "F.Mask" "F.Paste")
			(net 463 "VCC5V0_INT")
			(pinfunction "VIN")
			(pintype "power_in")
		)
		(pad "3" smd rect
			(at -1.45 -0.75 90)
			(size 0.35 0.8)
			(layers "F.Cu" "F.Mask" "F.Paste")
			(net 592 "/Supply/1V0_EN")
			(pinfunction "EN")
			(pintype "input")
		)
		(pad "4" smd rect
			(at -1.45 -0.25 90)
			(size 0.35 0.8)
			(layers "F.Cu" "F.Mask" "F.Paste")
			(net 612 "/Supply/1V0_MODE")
			(pinfunction "MODE")
			(pintype "input")
		)
		(pad "5" smd rect
			(at -1.45 0.248 90)
			(size 0.35 0.8)
			(layers "F.Cu" "F.Mask" "F.Paste")
			(net 611 "/Supply/1V0_FSEL")
			(pinfunction "FSEL")
			(pintype "input")
		)
		(pad "6" smd rect
			(at -1.45 0.748 90)
			(size 0.35 0.8)
			(layers "F.Cu" "F.Mask" "F.Paste")
			(net 658 "unconnected-(U12-PG-Pad6)")
			(pinfunction "PG")
			(pintype "open_collector+no_connect")
		)
		(pad "7" smd rect
			(at -0.5 0.949 180)
			(size 0.35 0.8)
			(layers "F.Cu" "F.Mask" "F.Paste")
			(net 581 "/Supply/1V0_BST")
			(pinfunction "BST")
			(pintype "input")
		)
		(pad "8" smd rect
			(at 0 0.55 90)
			(size 1.6 0.35)
			(layers "F.Cu" "F.Mask" "F.Paste")
			(net 582 "/Supply/1V0_SW")
			(pinfunction "SW")
			(pintype "output")
		)
		(pad "9" smd rect
			(at 1.449 0.748 270)
			(size 0.35 0.8)
			(layers "F.Cu" "F.Mask" "F.Paste")
			(net 593 "/Supply/1V0_VCC_INT")
			(pinfunction "VCC")
			(pintype "input")
		)
		(pad "10" smd rect
			(at 1.449 0.248 270)
			(size 0.35 0.8)
			(layers "F.Cu" "F.Mask" "F.Paste")
			(net 613 "/Supply/1V0_SS{slash}TR")
			(pinfunction "SS/TR")
			(pintype "input")
		)
		(pad "11" smd rect
			(at 1.449 -0.25 270)
			(size 0.35 0.8)
			(layers "F.Cu" "F.Mask" "F.Paste")
			(net 5 "GND")
			(pinfunction "GND")
			(pintype "passive")
		)
		(pad "12" smd rect
			(at 1.449 -0.75 270)
			(size 0.35 0.8)
			(layers "F.Cu" "F.Mask" "F.Paste")
			(net 599 "/Supply/1V0_FB")
			(pinfunction "FB")
			(pintype "input")
		)
	)
	(footprint "antmicro-footprints:R_0402_1005Metric"
		(layer "F.Cu")
		(at 184.1 111.85 -90)
		(descr "Resistor SMD 0402")
		(tags "resistor SMD 0402")
		(property "Reference" "R140"
			(at -0.75 -0.4 270)
			(layer "F.SilkS")
			(effects
				(font
					(size 0.7 0.7)
					(thickness 0.15)
				)
				(justify left bottom)
			)
		)
		(property "Value" "R_31k6_0402"
			(at 0 1.4 270)
			(layer "F.Fab")
			(effects
				(font
					(size 0.7 0.7)
					(thickness 0.15)
				)
				(justify left bottom)
			)
		)
		(property "Description" "31k6 resistor in 0402 package with 1% tolerance"
			(at 0 0 270)
			(layer "F.Fab")
			(hide yes)
			(effects
				(font
					(size 1.27 1.27)
					(thickness 0.15)
				)
			)
		)
		(property "Author" "Antmicro"
			(at 72.25 295.95 0)
			(layer "F.Fab")
			(hide yes)
			(effects
				(font
					(size 1 1)
					(thickness 0.15)
				)
			)
		)
		(property "License" "Apache-2.0"
			(at 72.25 295.95 0)
			(layer "F.Fab")
			(hide yes)
			(effects
				(font
					(size 1 1)
					(thickness 0.15)
				)
			)
		)
		(property "MPN" "CR0402-FX-3162GLF"
			(at 72.25 295.95 0)
			(layer "F.Fab")
			(hide yes)
			(effects
				(font
					(size 1 1)
					(thickness 0.15)
				)
			)
		)
		(property "Manufacturer" "Bourns"
			(at 72.25 295.95 0)
			(layer "F.Fab")
			(hide yes)
			(effects
				(font
					(size 1 1)
					(thickness 0.15)
				)
			)
		)
		(property "Tolerance" "1%"
			(at 72.25 295.95 0)
			(layer "F.Fab")
			(hide yes)
			(effects
				(font
					(size 1 1)
					(thickness 0.15)
				)
			)
		)
		(property "Val" "31k6"
			(at 72.25 295.95 0)
			(layer "F.Fab")
			(hide yes)
			(effects
				(font
					(size 1 1)
					(thickness 0.15)
				)
			)
		)
		(sheetname "Supply")
		(sheetfile "supply.kicad_sch")
		(attr smd)
		(fp_rect
			(start -0.93 -0.47)
			(end 0.93 0.47)
			(stroke
				(width 0.05)
				(type solid)
			)
			(fill no)
			(layer "F.CrtYd")
		)
		(fp_rect
			(start -0.5 -0.25)
			(end 0.5 0.25)
			(stroke
				(width 0.15)
				(type solid)
			)
			(fill no)
			(layer "F.Fab")
		)
		(pad "1" smd roundrect
			(at -0.485 0 270)
			(size 0.59 0.64)
			(layers "F.Cu" "F.Mask" "F.Paste")
			(roundrect_rratio 0.25)
			(net 589 "/Supply/1V2_REG")
			(pintype "passive")
		)
		(pad "2" smd roundrect
			(at 0.485 0 270)
			(size 0.59 0.64)
			(layers "F.Cu" "F.Mask" "F.Paste")
			(roundrect_rratio 0.25)
			(net 601 "/Supply/1V2_FB")
			(pintype "passive")
		)
	)
)
